FILE_TYPE = MACRO_DRAWING;
SET COLOR_WIRE YELLOW;
SET COLOR_PROP ORANGE;
SET COLOR_DOT WHITE;
SET COLOR_ARC YELLOW;
SET COLOR_BODY GREEN;
SET COLOR_NOTE PURPLE;
SET PROP_DISPLAY VALUE;
SET PAGE_NUMBER P440;
FORCEADD QUANTA_TITLE_BLOCK_C..1
(0 0);
FORCEPROP 1 LAST CUSTOM_TXT_CDS <NAME_2>
J 0
(-3175 50);
FORCEPROP 1 LAST CUSTOM_TXT_CDS <NAME_1>
J 0
(-3175 175);
FORCEPROP 1 LAST CUSTOM_TXT_CDS <Q_NUMBER>
J 0
(-1403 103);
DISPLAY 1.212766 (-1403 103);
FORCEPROP 1 LAST CUSTOM_TXT_CDS <Q_PROJ>
J 0
(-2382 102);
DISPLAY 1.212766 (-2382 102);
FORCEPROP 1 LAST CUSTOM_TXT_CDS <Q_REV>
J 0
(-184 103);
DISPLAY 1.212766 (-184 103);
FORCEPROP 1 LAST CUSTOM_TXT_CDS <CON_LAST_MODIFIED>
J 0
(-1885 15);
DISPLAY 0.978723 (-1885 15);
FORCEPROP 1 LAST CUSTOM_TXT_CDS <CON_PAGE_NUM> OF <CON_TOTAL_PAGES>
J 0
(-446 18);
DISPLAY 0.978723 (-446 18);
FORCEPROP 1 LAST Q_TITLE RETIMER_CPU1_P0 (9)
J 0
(-9366 26);
DISPLAY 2.446809 (-9366 26);
PAINT GREEN (-9366 26);
FORCEPROP 2 LAST PAGE_BORDER TRUE
J 0
(-7890 5250);
DISPLAY 0.638298 (-7890 5250);
PAINT PINK (-7890 5250);
DISPLAY INVISIBLE (-7890 5250);
FORCEPROP 1 LAST CDS_LMAN_SYM_OUTLINE -9475,6775,100,-125
J 0
(0 0);
DISPLAY 0.468085 (0 0);
PAINT GREEN (0 0);
DISPLAY INVISIBLE (0 0);
FORCEPROP 2 LAST CDS_LIB pure_quanta
J 0
(0 0);
DISPLAY INVISIBLE (0 0);
FORCEPROP 2 LAST CDS_XR_PAGE_TITLE CR-325 : @T6G_MB_LIB.T6G(SCH_1):PAGE325
J 0
(-7890 5250);
DISPLAY 0.638298 (-7890 5250);
PAINT PINK (-7890 5250);
DISPLAY INVISIBLE (-7890 5250);
FORCEPROP 2 LAST CUSTOM_TXT_CDS <XR_PAGE_TITLE>
J 0
(-7890 5250);
DISPLAY 0.638298 (-7890 5250);
PAINT PINK (-7890 5250);
DISPLAY INVISIBLE (-7890 5250);
FORCEPROP 1 LAST COMMENT_BODY TRUE
J 0
(12 -13);
DISPLAY 0.978723 (12 -13);
PAINT GREEN (12 -13);
DISPLAY INVISIBLE (12 -13);
FORCEPROP 1 LAST Q_DEPT BU9
J 1
(-3763 49);
DISPLAY 1.957447 (-3763 49);
PAINT GREEN (-3763 49);
DISPLAY INVISIBLE (-3763 49);
FORCEPROP 0 LAST CDS_CON_LAST_MODIFIED Thu Aug 24 10:16:45 2023
J 0
(-1885 15);
DISPLAY INVISIBLE (-1885 15);
QUIT
